# T6G (Grand Teton) — schematic netlist excerpt (pin names and nets, part order shuffled) for the footprints in the layout excerpt that follows; sources: Cadence DE-HDL packaged netlist, KiCad conversion of 04192023_DAF0TMB3IC0_F0TG_MB_C_brd_V02_OCP.brd

C6021  Q_CAP_DIFFBUS  DIFF BUS_0.33UF 6.3V 10% X6S  pkg C0402  page 180 : \1\ = USB3_CPU0_BMC_RX_DP ; \2\ = USB3_CPU0_BMC_RX_C2_DP
R3573  Q_RES  0 5% CHIP  pkg 0402LF  page 237 : A = SMB_INA230_4_3V3AUX_SDA_R ; B = SMB_INA230_4_3V3AUX_SDA_R1

(kicad_pcb
	(version 20260206)
	(generator "pcbnew")
	(generator_version "10.0")
	(general
		(thickness 1.6)
		(legacy_teardrops no)
	)
	(paper "A4")
	(title_block
		(title "04192023_DAF0TMB3IC0_F0TG_MB_C_brd_V02_OCP.brd")
		(comment 1 "Grand Teton / footprints 3266-3267 of 8354")
	)
	(layers
		(0 "F.Cu" signal "TOP")
		(4 "In1.Cu" signal "GND")
		(6 "In2.Cu" signal "IN1")
		(8 "In3.Cu" signal "GND1")
		(10 "In4.Cu" signal "IN2")
		(12 "In5.Cu" signal "GND2")
		(14 "In6.Cu" signal "IN3")
		(16 "In7.Cu" signal "GND3")
		(18 "In8.Cu" signal "VCC")
		(20 "In9.Cu" signal "VCC1")
		(22 "In10.Cu" signal "GND4")
		(24 "In11.Cu" signal "IN4")
		(26 "In12.Cu" signal "GND5")
		(28 "In13.Cu" signal "IN5")
		(30 "In14.Cu" signal "GND6")
		(32 "In15.Cu" signal "IN6")
		(34 "In16.Cu" signal "GND7")
		(2 "B.Cu" signal "BOTTOM")
		(9 "F.Adhes" user "F.Adhesive")
		(11 "B.Adhes" user "B.Adhesive")
		(13 "F.Paste" user "Package Geometry/Pastemask Top")
		(15 "B.Paste" user "Package Geometry/Pastemask Bottom")
		(5 "F.SilkS" user "Ref Des/Silkscreen Top")
		(7 "B.SilkS" user "Ref Des/Silkscreen Bottom")
		(1 "F.Mask" user "Board Geometry/Soldermask Top")
		(3 "B.Mask" user "Board Geometry/Soldermask Bottom")
		(17 "Dwgs.User" user "User.Drawings")
		(19 "Cmts.User" user "User.Comments")
		(21 "Eco1.User" user "User.Eco1")
		(23 "Eco2.User" user "User.Eco2")
		(25 "Edge.Cuts" user "Board Geometry/Outline")
		(27 "Margin" user)
		(31 "F.CrtYd" user "Package Geometry/Place Bound Top")
		(29 "B.CrtYd" user "Package Geometry/Place Bound Bottom")
		(35 "F.Fab" user "Ref Des/Assembly Top")
		(33 "B.Fab" user "Ref Des/Assembly Bottom")
	)
	(footprint ""
		(layer "F.Cu")
		(at 124.58827 -32.751268 180)
		(property "Reference" "C6021"
			(at 0 0 180)
			(layer "F.SilkS")
			(hide yes)
			(effects
				(font
					(size 1.27 1.27)
				)
			)
		)
		(property "Value" ""
			(at 0 0 180)
			(layer "F.Fab")
			(effects
				(font
					(size 1.27 1.27)
				)
			)
		)
		(duplicate_pad_numbers_are_jumpers no)
		(fp_line
			(start 0.40005 0.4064)
			(end -0.40005 0.4064)
			(stroke
				(width 0.1524)
				(type default)
			)
			(layer "F.SilkS")
		)
		(fp_line
			(start -0.40005 -0.4064)
			(end 0.40005 -0.4064)
			(stroke
				(width 0.1524)
				(type default)
			)
			(layer "F.SilkS")
		)
		(fp_line
			(start 0.6858 0.3048)
			(end 0.1016 0.3048)
			(stroke
				(width 0.1)
				(type default)
			)
			(layer "F.Fab")
		)
		(fp_line
			(start 0.6858 -0.3048)
			(end 0.6858 0.3048)
			(stroke
				(width 0.1)
				(type default)
			)
			(layer "F.Fab")
		)
		(fp_line
			(start 0.1016 0.3048)
			(end 0.1016 0.2794)
			(stroke
				(width 0.1)
				(type default)
			)
			(layer "F.Fab")
		)
		(fp_line
			(start 0.1016 0.2794)
			(end -0.1016 0.2794)
			(stroke
				(width 0.1)
				(type default)
			)
			(layer "F.Fab")
		)
		(fp_line
			(start 0.1016 -0.2794)
			(end 0.1016 -0.3048)
			(stroke
				(width 0.1)
				(type default)
			)
			(layer "F.Fab")
		)
		(fp_line
			(start 0.1016 -0.3048)
			(end 0.6858 -0.3048)
			(stroke
				(width 0.1)
				(type default)
			)
			(layer "F.Fab")
		)
		(fp_line
			(start -0.1016 0.3048)
			(end -0.6858 0.3048)
			(stroke
				(width 0.1)
				(type default)
			)
			(layer "F.Fab")
		)
		(fp_line
			(start -0.1016 0.2794)
			(end -0.1016 0.3048)
			(stroke
				(width 0.1)
				(type default)
			)
			(layer "F.Fab")
		)
		(fp_line
			(start -0.1016 -0.2794)
			(end 0.1016 -0.2794)
			(stroke
				(width 0.1)
				(type default)
			)
			(layer "F.Fab")
		)
		(fp_line
			(start -0.1016 -0.3048)
			(end -0.1016 -0.2794)
			(stroke
				(width 0.1)
				(type default)
			)
			(layer "F.Fab")
		)
		(fp_line
			(start -0.6858 0.3048)
			(end -0.6858 -0.3048)
			(stroke
				(width 0.1)
				(type default)
			)
			(layer "F.Fab")
		)
		(fp_line
			(start -0.6858 -0.3048)
			(end -0.1016 -0.3048)
			(stroke
				(width 0.1)
				(type default)
			)
			(layer "F.Fab")
		)
		(pad "1" smd rect
			(at -0.40005 0)
			(size 0.4572 0.508)
			(layers "F.Cu" "F.Mask" "F.Paste")
			(net "USB3_CPU0_BMC_RX_DP")
		)
		(pad "2" smd rect
			(at 0.40005 0)
			(size 0.4572 0.508)
			(layers "F.Cu" "F.Mask" "F.Paste")
			(net "USB3_CPU0_BMC_RX_C2_DP")
		)
	)
	(footprint ""
		(layer "F.Cu")
		(at 152.982422 -52.771294 90)
		(property "Reference" "R3573"
			(at 0 0 90)
			(layer "F.SilkS")
			(hide yes)
			(effects
				(font
					(size 1.27 1.27)
				)
			)
		)
		(property "Value" ""
			(at 0 0 90)
			(layer "F.Fab")
			(effects
				(font
					(size 1.27 1.27)
				)
			)
		)
		(duplicate_pad_numbers_are_jumpers no)
		(fp_line
			(start 0.7874 -0.4064)
			(end 0.7874 0.4064)
			(stroke
				(width 0.1524)
				(type default)
			)
			(layer "F.SilkS")
		)
		(fp_line
			(start -0.7874 -0.4064)
			(end 0.7874 -0.4064)
			(stroke
				(width 0.1524)
				(type default)
			)
			(layer "F.SilkS")
		)
		(fp_line
			(start 0.7874 0.4064)
			(end -0.7874 0.4064)
			(stroke
				(width 0.1524)
				(type default)
			)
			(layer "F.SilkS")
		)
		(fp_line
			(start -0.7874 0.4064)
			(end -0.7874 -0.4064)
			(stroke
				(width 0.1524)
				(type default)
			)
			(layer "F.SilkS")
		)
		(fp_line
			(start -0.12065 -0.305054)
			(end -0.12065 -0.2794)
			(stroke
				(width 0.1)
				(type default)
			)
			(layer "F.Fab")
		)
		(fp_line
			(start -0.67945 -0.305054)
			(end -0.12065 -0.305054)
			(stroke
				(width 0.1)
				(type default)
			)
			(layer "F.Fab")
		)
		(fp_line
			(start 0.67945 -0.3048)
			(end 0.67945 0.3048)
			(stroke
				(width 0.1)
				(type default)
			)
			(layer "F.Fab")
		)
		(fp_line
			(start 0.12065 -0.3048)
			(end 0.67945 -0.3048)
			(stroke
				(width 0.1)
				(type default)
			)
			(layer "F.Fab")
		)
		(fp_line
			(start 0.12065 -0.2794)
			(end 0.12065 -0.3048)
			(stroke
				(width 0.1)
				(type default)
			)
			(layer "F.Fab")
		)
		(fp_line
			(start -0.12065 -0.2794)
			(end 0.12065 -0.2794)
			(stroke
				(width 0.1)
				(type default)
			)
			(layer "F.Fab")
		)
		(fp_line
			(start 0.120396 0.2794)
			(end -0.12065 0.2794)
			(stroke
				(width 0.1)
				(type default)
			)
			(layer "F.Fab")
		)
		(fp_line
			(start -0.12065 0.2794)
			(end -0.12065 0.3048)
			(stroke
				(width 0.1)
				(type default)
			)
			(layer "F.Fab")
		)
		(fp_line
			(start 0.67945 0.3048)
			(end 0.120396 0.3048)
			(stroke
				(width 0.1)
				(type default)
			)
			(layer "F.Fab")
		)
		(fp_line
			(start 0.120396 0.3048)
			(end 0.120396 0.2794)
			(stroke
				(width 0.1)
				(type default)
			)
			(layer "F.Fab")
		)
		(fp_line
			(start -0.12065 0.3048)
			(end -0.67945 0.3048)
			(stroke
				(width 0.1)
				(type default)
			)
			(layer "F.Fab")
		)
		(fp_line
			(start -0.67945 0.3048)
			(end -0.67945 -0.305054)
			(stroke
				(width 0.1)
				(type default)
			)
			(layer "F.Fab")
		)
		(pad "1" smd circle
			(at -0.40005 0 90)
			(size 0 0)
			(layers "F.Cu" "F.Mask" "F.Paste")
			(net "SMB_INA230_4_3V3AUX_SDA_R")
		)
		(pad "2" smd circle
			(at 0.40005 0 90)
			(size 0 0)
			(layers "F.Cu" "F.Mask" "F.Paste")
			(net "SMB_INA230_4_3V3AUX_SDA_R1")
		)
	)
)
